FILE_TYPE = CONNECTIVITY;
{Allegro Design Entry HDL 17.4-2019 S026 (4007227) 1/17/2022}
"PAGE_NUMBER" = 104;
0"NC";
1"GND\g";
2"GND\g";
3"P3V3\g";
4"M_H_CPU1_SB_CB<7:0>";
5"M_H_CPU1_SA_CB<7:0>";
6"M_H_CPU1_SA_DQ<31:0>";
7"M_H_CPU1_SA_DQS_DN<9:0>";
8"M_H_CPU1_SB_DQS_DP<9:0>";
9"M_H_CPU1_SB_DQS_DN<9:0>";
10"M_H_CPU1_SA_DQS_DP<9:0>";
11"M_H_CPU1_SA_CA<6:0>";
12"M_H_CPU1_SB_DQ<31:0>";
13"M_H_CPU1_SB_CA<6:0>";
14"PWRGD_CHH_CPU1_DIMM";
15"M_H_CPU1_ALERT_N";
16"M_H_CPU1_RESET_N";
17"M_H_CPU1_SB_CB<0>";
18"M_H_CPU1_SB_DQ<15>";
19"M_H_CPU1_SA_CB<0>";
20"PD_CHH_CPU1_DIMM_SAA";
21"M_H_CPU1_SA_DQ<31>";
22"M_H_CPU1_SA_CB<7>";
23"M_H_CPU1_SA_CB<4>";
24"M_H_CPU1_SA_CA<0>";
25"M_H_CPU1_SB_CA<0>";
26"M_H_CPU1_SA_CA<1>";
27"M_H_CPU1_SB_CA<1>";
28"M_H_CPU1_SA_CA<2>";
29"M_H_CPU1_SB_CA<2>";
30"M_H_CPU1_SA_CA<3>";
31"M_H_CPU1_SB_CA<3>";
32"M_H_CPU1_SB_CA<4>";
33"M_H_CPU1_SB_CA<5>";
34"M_H_CPU1_SA_CA<6>";
35"M_H_CPU1_SB_CA<6>";
36"M_H_CPU1_SA_CB<6>";
37"M_H_CPU1_SA_CB<5>";
38"M_H_CPU1_SA_CB<3>";
39"M_H_CPU1_SA_CB<2>";
40"M_H_CPU1_SB_CB<6>";
41"M_H_CPU1_SB_CB<5>";
42"M_H_CPU1_SB_CB<4>";
43"M_H_CPU1_SB_CB<3>";
44"M_H_CPU1_SB_CB<2>";
45"M_H_CPU1_SB_CB<1>";
46"M_H_CPU1_CLK_DN<0>";
47"M_H_CPU1_CLK_DP<0>";
48"M_H_CPU1_SA_CS_N<0>";
49"M_H_CPU1_SB_CS_N<0>";
50"M_H_CPU1_SA_CS_N<1>";
51"M_H_CPU1_SB_CS_N<1>";
52"M_H_CPU1_SA_DQ<27>";
53"M_H_CPU1_SA_DQ<26>";
54"M_H_CPU1_SA_DQ<25>";
55"M_H_CPU1_SA_DQ<24>";
56"M_H_CPU1_SA_DQ<23>";
57"M_H_CPU1_SA_DQ<22>";
58"M_H_CPU1_SA_DQ<21>";
59"M_H_CPU1_SA_DQ<20>";
60"M_H_CPU1_SA_DQ<19>";
61"M_H_CPU1_SA_DQ<18>";
62"M_H_CPU1_SA_DQ<17>";
63"M_H_CPU1_SA_DQ<14>";
64"M_H_CPU1_SA_DQ<13>";
65"M_H_CPU1_SA_DQ<12>";
66"M_H_CPU1_SA_DQ<11>";
67"M_H_CPU1_SA_DQ<10>";
68"M_H_CPU1_SA_DQ<9>";
69"M_H_CPU1_SA_DQ<8>";
70"M_H_CPU1_SA_DQ<7>";
71"M_H_CPU1_SA_DQ<6>";
72"M_H_CPU1_SA_DQ<5>";
73"M_H_CPU1_SA_DQ<4>";
74"M_H_CPU1_SA_DQ<3>";
75"M_H_CPU1_SA_DQ<2>";
76"M_H_CPU1_SA_DQ<1>";
77"M_H_CPU1_SA_DQ<0>";
78"M_H_CPU1_SB_DQ<31>";
79"M_H_CPU1_SB_DQ<30>";
80"M_H_CPU1_SB_DQ<29>";
81"M_H_CPU1_SB_DQ<28>";
82"M_H_CPU1_SB_DQ<27>";
83"M_H_CPU1_SB_DQ<26>";
84"M_H_CPU1_SB_DQ<25>";
85"M_H_CPU1_SB_DQ<24>";
86"M_H_CPU1_SB_DQ<23>";
87"M_H_CPU1_SB_DQ<22>";
88"M_H_CPU1_SB_DQ<21>";
89"M_H_CPU1_SB_DQ<20>";
90"M_H_CPU1_SB_DQ<19>";
91"M_H_CPU1_SB_DQ<18>";
92"M_H_CPU1_SB_DQ<17>";
93"M_H_CPU1_SB_DQ<16>";
94"M_H_CPU1_SB_DQ<14>";
95"M_H_CPU1_SB_DQ<13>";
96"M_H_CPU1_SB_DQ<12>";
97"M_H_CPU1_SB_DQ<11>";
98"M_H_CPU1_SB_DQ<10>";
99"M_H_CPU1_SB_DQ<9>";
100"M_H_CPU1_SB_DQ<8>";
101"M_H_CPU1_SB_DQ<7>";
102"M_H_CPU1_SB_DQ<6>";
103"M_H_CPU1_SB_DQ<5>";
104"M_H_CPU1_SB_DQ<4>";
105"M_H_CPU1_SB_DQ<3>";
106"M_H_CPU1_SB_DQ<2>";
107"M_H_CPU1_SB_DQ<1>";
108"M_H_CPU1_SB_DQ<0>";
109"M_H_CPU1_SA_RSP<0>";
110"M_H_CPU1_SB_RSP<0>";
111"M_H_CPU1_SA_PAR";
112"M_H_CPU1_SB_PAR";
113"M_H_CPU1_SA_DQ<28>";
114"M_H_CPU1_SA_DQ<30>";
115"M_H_CPU1_SA_DQ<29>";
116"M_H_CPU1_SA_CA<4>";
117"M_H_CPU1_SA_CA<5>";
118"M_H_CPU1_SA_DQS_DN<7>";
119"M_H_CPU1_SA_DQS_DP<6>";
120"M_H_CPU1_SB_DQS_DP<8>";
121"M_H_CPU1_SB_DQS_DN<8>";
122"M_H_CPU1_SB_DQS_DP<7>";
123"M_H_CPU1_SA_DQS_DN<0>";
124"M_H_CPU1_SA_DQS_DP<0>";
125"M_H_CPU1_SB_DQS_DN<0>";
126"M_H_CPU1_SB_DQS_DP<0>";
127"M_H_CPU1_SA_DQS_DN<1>";
128"M_H_CPU1_SA_DQS_DP<1>";
129"M_H_CPU1_SB_DQS_DN<1>";
130"M_H_CPU1_SB_DQS_DP<1>";
131"M_H_CPU1_SA_DQS_DN<2>";
132"M_H_CPU1_SA_DQS_DP<2>";
133"M_H_CPU1_SB_DQS_DN<2>";
134"M_H_CPU1_SB_DQS_DP<2>";
135"M_H_CPU1_SA_DQS_DN<3>";
136"M_H_CPU1_SA_DQS_DP<3>";
137"M_H_CPU1_SB_DQS_DN<3>";
138"M_H_CPU1_SB_DQS_DP<3>";
139"M_H_CPU1_SA_DQS_DN<4>";
140"M_H_CPU1_SA_DQS_DP<4>";
141"M_H_CPU1_SB_DQS_DN<4>";
142"M_H_CPU1_SB_DQS_DP<4>";
143"M_H_CPU1_SA_DQS_DN<5>";
144"M_H_CPU1_SA_DQS_DP<5>";
145"M_H_CPU1_SB_DQS_DN<5>";
146"M_H_CPU1_SB_DQS_DP<5>";
147"M_H_CPU1_SA_DQS_DN<6>";
148"M_H_CPU1_SB_DQS_DN<6>";
149"M_H_CPU1_SB_DQS_DP<6>";
150"M_H_CPU1_SA_DQS_DP<7>";
151"M_H_CPU1_SB_DQS_DN<7>";
152"M_H_CPU1_SA_DQS_DN<8>";
153"M_H_CPU1_SA_DQS_DP<8>";
154"M_H_CPU1_SA_DQS_DP<9>";
155"M_H_CPU1_SB_DQS_DN<9>";
156"M_H_CPU1_SB_DQS_DP<9>";
157"M_H_CPU1_SA_DQS_DN<9>";
158"M_H_CPU1_SA_DQ<16>";
159"M_H_CPU1_SA_DQ<15>";
160"M_H_CPU1_SA_CB<1>";
161"M_H_CPU1_SB_CB<7>";
162"PWRGD_CHGL_CPU1";
163"P12V_MEM_CPU1\g";
164"GND\g";
165"GND\g";
166"GND\g";
167"PD_CHH_CPU1_DIMM_SAA";
168"I3C_SPD_DDRH_CPU1_SCL";
169"I3C_SPD_DDRGL_CPU1_SDA";
170"I3C_SPD_DDRGL_CPU1_SCL";
171"I3C_SPD_DDRH_CPU1_SDA";
172"P3V3_AUX\g";
%"TAP"
"1","(-5950,4200)","0","mstr_standard","I100";
;
CDS_LIB"mstr_standard"
BODY_TYPE"PLUMBING"
HDL_TAP"TRUE";
"B \NAC \NWC"6;
"S \NAC"
BN"7"70;
%"TAP"
"1","(-5950,4250)","0","mstr_standard","I101";
;
CDS_LIB"mstr_standard"
BODY_TYPE"PLUMBING"
HDL_TAP"TRUE";
"B \NAC \NWC"6;
"S \NAC"
BN"8"69;
%"TAP"
"1","(-5950,4300)","0","mstr_standard","I102";
;
CDS_LIB"mstr_standard"
BODY_TYPE"PLUMBING"
HDL_TAP"TRUE";
"B \NAC \NWC"6;
"S \NAC"
BN"9"68;
%"TAP"
"1","(-5950,4400)","0","mstr_standard","I103";
;
CDS_LIB"mstr_standard"
BODY_TYPE"PLUMBING"
HDL_TAP"TRUE";
"B \NAC \NWC"6;
"S \NAC"
BN"11"66;
%"TAP"
"1","(-5950,4350)","0","mstr_standard","I104";
;
CDS_LIB"mstr_standard"
BODY_TYPE"PLUMBING"
HDL_TAP"TRUE";
"B \NAC \NWC"6;
"S \NAC"
BN"10"67;
%"TAP"
"1","(-5950,4450)","0","mstr_standard","I105";
;
CDS_LIB"mstr_standard"
BODY_TYPE"PLUMBING"
HDL_TAP"TRUE";
"B \NAC \NWC"6;
"S \NAC"
BN"12"65;
%"TAP"
"1","(-5950,4500)","0","mstr_standard","I106";
;
CDS_LIB"mstr_standard"
BODY_TYPE"PLUMBING"
HDL_TAP"TRUE";
"B \NAC \NWC"6;
"S \NAC"
BN"13"64;
%"TAP"
"1","(-5950,4550)","0","mstr_standard","I107";
;
CDS_LIB"mstr_standard"
BODY_TYPE"PLUMBING"
HDL_TAP"TRUE";
"B \NAC \NWC"6;
"S \NAC"
BN"14"63;
%"TAP"
"1","(-5950,4650)","0","mstr_standard","I108";
;
CDS_LIB"mstr_standard"
BODY_TYPE"PLUMBING"
HDL_TAP"TRUE";
"B \NAC \NWC"6;
"S \NAC"
BN"16"158;
%"TAP"
"1","(-5950,4600)","0","mstr_standard","I109";
;
CDS_LIB"mstr_standard"
BODY_TYPE"PLUMBING"
HDL_TAP"TRUE";
"B \NAC \NWC"6;
"S \NAC"
BN"15"159;
%"TAP"
"1","(-5950,4750)","0","mstr_standard","I110";
;
CDS_LIB"mstr_standard"
BODY_TYPE"PLUMBING"
HDL_TAP"TRUE";
"B \NAC \NWC"6;
"S \NAC"
BN"18"61;
%"TAP"
"1","(-5950,4700)","0","mstr_standard","I111";
;
CDS_LIB"mstr_standard"
BODY_TYPE"PLUMBING"
HDL_TAP"TRUE";
"B \NAC \NWC"6;
"S \NAC"
BN"17"62;
%"TAP"
"1","(-5950,4800)","0","mstr_standard","I112";
;
CDS_LIB"mstr_standard"
BODY_TYPE"PLUMBING"
HDL_TAP"TRUE";
"B \NAC \NWC"6;
"S \NAC"
BN"19"60;
%"TAP"
"1","(-5950,4900)","0","mstr_standard","I113";
;
CDS_LIB"mstr_standard"
BODY_TYPE"PLUMBING"
HDL_TAP"TRUE";
"B \NAC \NWC"6;
"S \NAC"
BN"21"58;
%"TAP"
"1","(-5950,4850)","0","mstr_standard","I114";
;
CDS_LIB"mstr_standard"
BODY_TYPE"PLUMBING"
HDL_TAP"TRUE";
"B \NAC \NWC"6;
"S \NAC"
BN"20"59;
%"TAP"
"1","(-5950,4950)","0","mstr_standard","I115";
;
CDS_LIB"mstr_standard"
BODY_TYPE"PLUMBING"
HDL_TAP"TRUE";
"B \NAC \NWC"6;
"S \NAC"
BN"22"57;
%"TAP"
"1","(-5950,5000)","0","mstr_standard","I116";
;
CDS_LIB"mstr_standard"
BODY_TYPE"PLUMBING"
HDL_TAP"TRUE";
"B \NAC \NWC"6;
"S \NAC"
BN"23"56;
%"TAP"
"1","(-5950,5100)","0","mstr_standard","I117";
;
CDS_LIB"mstr_standard"
BODY_TYPE"PLUMBING"
HDL_TAP"TRUE";
"B \NAC \NWC"6;
"S \NAC"
BN"25"54;
%"TAP"
"1","(-5950,5050)","0","mstr_standard","I118";
;
CDS_LIB"mstr_standard"
BODY_TYPE"PLUMBING"
HDL_TAP"TRUE";
"B \NAC \NWC"6;
"S \NAC"
BN"24"55;
%"TAP"
"1","(-5950,5150)","0","mstr_standard","I119";
;
CDS_LIB"mstr_standard"
BODY_TYPE"PLUMBING"
HDL_TAP"TRUE";
"B \NAC \NWC"6;
"S \NAC"
BN"26"53;
%"TAP"
"1","(-5950,5300)","0","mstr_standard","I120";
;
CDS_LIB"mstr_standard"
BODY_TYPE"PLUMBING"
HDL_TAP"TRUE";
"B \NAC \NWC"6;
"S \NAC"
BN"29"115;
%"TAP"
"1","(-5950,5250)","0","mstr_standard","I121";
;
CDS_LIB"mstr_standard"
BODY_TYPE"PLUMBING"
HDL_TAP"TRUE";
"B \NAC \NWC"6;
"S \NAC"
BN"28"113;
%"TAP"
"1","(-5950,5200)","0","mstr_standard","I122";
;
CDS_LIB"mstr_standard"
BODY_TYPE"PLUMBING"
HDL_TAP"TRUE";
"B \NAC \NWC"6;
"S \NAC"
BN"27"52;
%"TAP"
"1","(-5950,5350)","0","mstr_standard","I123";
;
CDS_LIB"mstr_standard"
BODY_TYPE"PLUMBING"
HDL_TAP"TRUE";
"B \NAC \NWC"6;
"S \NAC"
BN"30"114;
%"TAP"
"1","(-5950,5400)","0","mstr_standard","I124";
;
CDS_LIB"mstr_standard"
BODY_TYPE"PLUMBING"
HDL_TAP"TRUE";
"B \NAC \NWC"6;
"S \NAC"
BN"31"21;
%"GND"
"1","(-6375,850)","0","mstr_symbols","I127";
;
SIZE"1B"
CDS_LIB"mstr_symbols"
BOM_COST"MEM"
VOLTAGE"0.0"
BODY_TYPE"PLUMBING"
HDL_POWER"GND";
"A\NAC"1;
%"Q_RES"
"2","(-6375,1075)","0","pure_quanta","I128";
;
LOCATION"R774"
$SEC"1"
CDS_SEC"1"
WATTAGE"1/16W"
MATERIAL"CHIP"
TOLERANCE"1%"
VALUE"15.4K"
PACK_TYPE"0402LF"
CDS_LIB"pure_quanta"
PART_NUMBER"CS31542FB02";
"A"
$PN"1"20;
"B"
$PN"2"1;
%"GND"
"1","(-2125,1875)","0","mstr_symbols","I140";
;
SIZE"1B"
CDS_LIB"mstr_symbols"
VOLTAGE"0.0"
BODY_TYPE"PLUMBING"
HDL_POWER"GND";
"A\NAC"166;
%"GND"
"1","(-325,1650)","0","mstr_symbols","I141";
;
SIZE"1B"
CDS_LIB"mstr_symbols"
VOLTAGE"0.0"
BODY_TYPE"PLUMBING"
HDL_POWER"GND";
"A\NAC"165;
%"SCONN288_DDR506112002KQ"
"3","(-1225,3650)","0","pure_quanta","I174";
;
LOCATION"J27"
$SEC"3"
CDS_SEC"3"
PART_TYPE"SMLF"
MATERIAL"IO"
VALUE"SCONN288_DDR506112002KQ"
CDS_LMAN_SYM_OUTLINE"-450,1800,450,-1750"
NEEDS_NO_SIZE"TRUE"
CDS_LIB"pure_quanta"
PART_NUMBER"DFHST8FS479";
"G3"
$PN"G3"165;
"G2"
$PN"G2"165;
"G1"
$PN"G1"165;
"VSS62"
$PN"141"165;
"VSS61"
$PN"139"165;
"VSS60"
$PN"136"165;
"VSS58"
$PN"132"165;
"VSS104"
$PN"240"166;
"VSS102"
$PN"235"166;
"VSS100"
$PN"230"166;
"VIN_BULK2"
$PN"146"163;
"VIN_BULK1"
$PN"145"163;
"VIN_BULK0"
$PN"1"163;
"VSS126"
$PN"288"166;
"VSS125"
$PN"286"166;
"VSS124"
$PN"284"166;
"VSS123"
$PN"281"166;
"VSS122"
$PN"279"166;
"VSS121"
$PN"277"166;
"VSS120"
$PN"275"166;
"VSS119"
$PN"273"166;
"VSS118"
$PN"270"166;
"VSS117"
$PN"268"166;
"VSS116"
$PN"266"166;
"VSS115"
$PN"264"166;
"VSS114"
$PN"262"166;
"VSS113"
$PN"259"166;
"VSS112"
$PN"257"166;
"VSS111"
$PN"255"166;
"VSS110"
$PN"253"166;
"VSS109"
$PN"251"166;
"VSS108"
$PN"248"166;
"VSS107"
$PN"246"166;
"VSS106"
$PN"244"166;
"VSS105"
$PN"242"166;
"VSS103"
$PN"237"166;
"VSS101"
$PN"233"166;
"VSS99"
$PN"228"166;
"VSS98"
$PN"226"166;
"VSS97"
$PN"224"166;
"VSS96"
$PN"222"166;
"VSS95"
$PN"219"166;
"VSS94"
$PN"216"166;
"VSS93"
$PN"214"166;
"VSS92"
$PN"212"166;
"VSS91"
$PN"210"166;
"VSS90"
$PN"208"166;
"VSS89"
$PN"206"166;
"VSS88"
$PN"204"166;
"VSS87"
$PN"202"166;
"VSS86"
$PN"199"166;
"VSS85"
$PN"197"166;
"VSS84"
$PN"195"166;
"VSS83"
$PN"193"166;
"VSS82"
$PN"191"166;
"VSS81"
$PN"188"166;
"VSS80"
$PN"186"166;
"VSS79"
$PN"184"166;
"VSS78"
$PN"182"166;
"VSS77"
$PN"180"166;
"VSS76"
$PN"177"166;
"VSS75"
$PN"175"166;
"VSS74"
$PN"173"166;
"VSS73"
$PN"171"166;
"VSS72"
$PN"169"166;
"VSS71"
$PN"166"166;
"VSS70"
$PN"164"166;
"VSS69"
$PN"162"166;
"VSS68"
$PN"160"166;
"VSS67"
$PN"158"166;
"VSS66"
$PN"155"166;
"VSS65"
$PN"153"166;
"VSS64"
$PN"151"166;
"VSS63"
$PN"143"165;
"VSS59"
$PN"134"165;
"VSS57"
$PN"130"165;
"VSS56"
$PN"128"165;
"VSS55"
$PN"125"165;
"VSS54"
$PN"123"165;
"VSS53"
$PN"121"165;
"VSS52"
$PN"119"165;
"VSS51"
$PN"117"165;
"VSS50"
$PN"114"165;
"VSS49"
$PN"112"165;
"VSS48"
$PN"110"165;
"VSS47"
$PN"108"165;
"VSS46"
$PN"106"165;
"VSS45"
$PN"103"165;
"VSS44"
$PN"101"165;
"VSS43"
$PN"99"165;
"VSS42"
$PN"97"165;
"VSS41"
$PN"95"165;
"VSS40"
$PN"92"165;
"VSS39"
$PN"90"165;
"VSS38"
$PN"88"165;
"VSS37"
$PN"85"165;
"VSS36"
$PN"83"165;
"VSS35"
$PN"81"165;
"VSS34"
$PN"79"165;
"VSS33"
$PN"77"165;
"VSS32"
$PN"75"165;
"VSS31"
$PN"73"165;
"VSS30"
$PN"71"165;
"VSS29"
$PN"69"165;
"VSS28"
$PN"67"165;
"VSS27"
$PN"65"165;
"VSS26"
$PN"63"165;
"VSS25"
$PN"61"165;
"VSS24"
$PN"59"165;
"VSS23"
$PN"57"165;
"VSS22"
$PN"54"165;
"VSS21"
$PN"52"165;
"VSS20"
$PN"50"165;
"VSS19"
$PN"48"165;
"VSS18"
$PN"46"165;
"VSS17"
$PN"43"165;
"VSS16"
$PN"41"165;
"VSS15"
$PN"39"165;
"VSS14"
$PN"37"165;
"VSS13"
$PN"35"165;
"VSS12"
$PN"32"165;
"VSS11"
$PN"30"165;
"VSS10"
$PN"28"165;
"VSS9"
$PN"26"165;
"VSS8"
$PN"24"165;
"VSS7"
$PN"21"165;
"VSS6"
$PN"19"165;
"VSS5"
$PN"17"165;
"VSS4"
$PN"15"165;
"VSS3"
$PN"13"165;
"VSS2"
$PN"10"165;
"VSS1"
$PN"8"165;
"VSS0"
$PN"6"165;
%"Q_CAP"
"1","(-8575,3225)","2","pure_quanta","I185";
;
LOCATION"C164"
$SEC"1"
CDS_SEC"1"
PACK_TYPE"0402"
VALUE"0.1UF"
VOLTAGE"25V"
TOLERANCE"10%"
MATERIAL"X7R"
CDS_LIB"pure_quanta"
BOM_COST"MEM"
ROOM""
PART_NUMBER"CH4104K1B00";
"B"
$PN"2"2;
"A"
$PN"1"172;
%"GND"
"1","(-8575,3000)","0","mstr_symbols","I186";
;
BOM_COST"MEM"
SIZE"1B"
CDS_LIB"mstr_symbols"
VOLTAGE"0"
ROOM"MEM_EFGH_DECOUPLING_CAPS"
BODY_TYPE"PLUMBING"
HDL_POWER"GND";
"A\NAC"2;
%"Q_RES"
"1","(-8475,2150)","2","pure_quanta","I189";
;
LOCATION"R310"
$SEC"1"
CDS_SEC"1"
VALUE"1K"
TOLERANCE"1%"
BOM_COST"MEM"
CDS_LIB"pure_quanta"
WATTAGE"1/16W"
MATERIAL"CHIP"
PACK_TYPE"0402LF"
ROOM""
PART_NUMBER"CS21002FB06";
"B"
$PN"2"162;
"A"
$PN"1"14;
%"Q_RES"
"2","(-8350,2300)","0","pure_quanta","I190";
;
LOCATION"R111"
$SEC"1"
CDS_SEC"1"
TOLERANCE"1%"
WATTAGE"1/16W"
MATERIAL"EMPTY"
PACK_TYPE"0402LF"
VALUE"1K"
BOM_COST"MEM"
CDS_LIB"pure_quanta"
ROOM""
PART_NUMBER"CS21002FB06";
"A"
$PN"1"3;
"B"
$PN"2"14;
%"VCC_CORE"
"1","(-8350,2475)","0","mstr_symbols","I192";
;
HDL_POWER"P3V3"
CDS_LIB"mstr_symbols"
VOLTAGE"3.3"
ROOM"PVCCINFAON_CPU0_CTRL";
"A"3;
%"TAP"
"1","(-3225,3675)","0","mstr_standard","I193";
;
CDS_LIB"mstr_standard"
BODY_TYPE"PLUMBING"
HDL_TAP"TRUE";
"B \NAC \NWC"7;
"S \NAC"
BN"2"131;
%"TAP"
"1","(-3225,3775)","0","mstr_standard","I194";
;
CDS_LIB"mstr_standard"
BODY_TYPE"PLUMBING"
HDL_TAP"TRUE";
"B \NAC \NWC"7;
"S \NAC"
BN"3"135;
%"TAP"
"1","(-3425,3925)","0","mstr_standard","I195";
;
CDS_LIB"mstr_standard"
BODY_TYPE"PLUMBING"
HDL_TAP"TRUE";
"B \NAC \NWC"10;
"S \NAC"
BN"4"140;
%"TAP"
"1","(-3425,4025)","0","mstr_standard","I196";
;
CDS_LIB"mstr_standard"
BODY_TYPE"PLUMBING"
HDL_TAP"TRUE";
"B \NAC \NWC"10;
"S \NAC"
BN"5"144;
%"TAP"
"1","(-3225,4375)","0","mstr_standard","I202";
;
CDS_LIB"mstr_standard"
BODY_TYPE"PLUMBING"
HDL_TAP"TRUE";
"B \NAC \NWC"7;
"S \NAC"
BN"9"157;
%"TAP"
"1","(-3225,4275)","0","mstr_standard","I203";
;
CDS_LIB"mstr_standard"
BODY_TYPE"PLUMBING"
HDL_TAP"TRUE";
"B \NAC \NWC"7;
"S \NAC"
BN"8"152;
%"TAP"
"1","(-3425,4425)","0","mstr_standard","I204";
;
CDS_LIB"mstr_standard"
BODY_TYPE"PLUMBING"
HDL_TAP"TRUE";
"B \NAC \NWC"10;
"S \NAC"
BN"9"154;
%"TAP"
"1","(-3425,4325)","0","mstr_standard","I205";
;
CDS_LIB"mstr_standard"
BODY_TYPE"PLUMBING"
HDL_TAP"TRUE";
"B \NAC \NWC"10;
"S \NAC"
BN"8"153;
%"TAP"
"1","(-3225,4175)","0","mstr_standard","I206";
;
CDS_LIB"mstr_standard"
BODY_TYPE"PLUMBING"
HDL_TAP"TRUE";
"B \NAC \NWC"7;
"S \NAC"
BN"7"118;
%"TAP"
"1","(-3225,4075)","0","mstr_standard","I207";
;
CDS_LIB"mstr_standard"
BODY_TYPE"PLUMBING"
HDL_TAP"TRUE";
"B \NAC \NWC"7;
"S \NAC"
BN"6"147;
%"TAP"
"1","(-3225,3975)","0","mstr_standard","I208";
;
CDS_LIB"mstr_standard"
BODY_TYPE"PLUMBING"
HDL_TAP"TRUE";
"B \NAC \NWC"7;
"S \NAC"
BN"5"143;
%"TAP"
"1","(-3225,3875)","0","mstr_standard","I209";
;
CDS_LIB"mstr_standard"
BODY_TYPE"PLUMBING"
HDL_TAP"TRUE";
"B \NAC \NWC"7;
"S \NAC"
BN"4"139;
%"TAP"
"1","(-3225,3575)","0","mstr_standard","I210";
;
CDS_LIB"mstr_standard"
BODY_TYPE"PLUMBING"
HDL_TAP"TRUE";
"B \NAC \NWC"7;
"S \NAC"
BN"1"127;
%"TAP"
"1","(-3225,3475)","0","mstr_standard","I211";
;
CDS_LIB"mstr_standard"
BODY_TYPE"PLUMBING"
HDL_TAP"TRUE";
"B \NAC \NWC"7;
"S \NAC"
BN"0"123;
%"TAP"
"1","(-3225,3225)","0","mstr_standard","I212";
;
CDS_LIB"mstr_standard"
BODY_TYPE"PLUMBING"
HDL_TAP"TRUE";
"B \NAC \NWC"9;
"S \NAC"
BN"8"121;
%"TAP"
"1","(-3225,3325)","0","mstr_standard","I213";
;
CDS_LIB"mstr_standard"
BODY_TYPE"PLUMBING"
HDL_TAP"TRUE";
"B \NAC \NWC"9;
"S \NAC"
BN"9"155;
%"TAP"
"1","(-3425,4225)","0","mstr_standard","I214";
;
CDS_LIB"mstr_standard"
BODY_TYPE"PLUMBING"
HDL_TAP"TRUE";
"B \NAC \NWC"10;
"S \NAC"
BN"7"150;
%"TAP"
"1","(-3425,4125)","0","mstr_standard","I215";
;
CDS_LIB"mstr_standard"
BODY_TYPE"PLUMBING"
HDL_TAP"TRUE";
"B \NAC \NWC"10;
"S \NAC"
BN"6"119;
%"TAP"
"1","(-3425,3825)","0","mstr_standard","I216";
;
CDS_LIB"mstr_standard"
BODY_TYPE"PLUMBING"
HDL_TAP"TRUE";
"B \NAC \NWC"10;
"S \NAC"
BN"3"136;
%"TAP"
"1","(-3425,3725)","0","mstr_standard","I217";
;
CDS_LIB"mstr_standard"
BODY_TYPE"PLUMBING"
HDL_TAP"TRUE";
"B \NAC \NWC"10;
"S \NAC"
BN"2"132;
%"TAP"
"1","(-3425,3625)","0","mstr_standard","I218";
;
CDS_LIB"mstr_standard"
BODY_TYPE"PLUMBING"
HDL_TAP"TRUE";
"B \NAC \NWC"10;
"S \NAC"
BN"1"128;
%"TAP"
"1","(-3425,3525)","0","mstr_standard","I219";
;
CDS_LIB"mstr_standard"
BODY_TYPE"PLUMBING"
HDL_TAP"TRUE";
"B \NAC \NWC"10;
"S \NAC"
BN"0"124;
%"SCONN288_DDR506112002KQ"
"1","(-6800,3650)","0","pure_quanta","I22";
;
LOCATION"J27"
$SEC"1"
CDS_SEC"1"
VALUE"SCONN288_DDR506112002KQ"
PART_TYPE"SMLF"
MATERIAL"IO"
CDS_LMAN_SYM_OUTLINE"-450,1900,450,-1850"
NEEDS_NO_SIZE"TRUE"
CDS_LIB"pure_quanta"
PART_NUMBER"DFHST8FS479";
"PWR_GOOD||FAIL_N"
$PN"147"14;
"DQ31_A"
$PN"194"21;
"CB7_A"
$PN"205"22;
"CB4_A"
$PN"58"23;
"CB1_A"
$PN"53"160;
"CB7_B"
$PN"236"161;
"ALERT_N \B"
$PN"62"15;
"CA0_A"
$PN"66"24;
"CA0_B"
$PN"76"25;
"CA1_A"
$PN"211"26;
"CA1_B"
$PN"221"27;
"CA2_A"
$PN"68"28;
"CA2_B"
$PN"78"29;
"CA3_A"
$PN"213"30;
"CA3_B"
$PN"223"31;
"CA4_A"
$PN"70"116;
"CA4_B"
$PN"80"32;
"CA5_A"
$PN"215"117;
"CA5_B"
$PN"225"33;
"CA6_A"
$PN"72"34;
"CA6_B"
$PN"82"35;
"CB6_A"
$PN"203"36;
"CB5_A"
$PN"60"37;
"CB3_A"
$PN"198"38;
"CB2_A"
$PN"196"39;
"CB0_A"
$PN"51"19;
"CB6_B"
$PN"234"40;
"CB5_B"
$PN"91"41;
"CB4_B"
$PN"89"42;
"CB3_B"
$PN"243"43;
"CB2_B"
$PN"241"44;
"CB1_B"
$PN"98"45;
"CB0_B"
$PN"96"17;
"CK_C \B"
$PN"218"46;
"CK_T"
$PN"217"47;
"CS0_A_N"
$PN"64"48;
"CS0_B_N"
$PN"84"49;
"CS1_A_N"
$PN"209"50;
"CS1_B_N"
$PN"229"51;
"DQ30_A"
$PN"192"114;
"DQ29_A"
$PN"49"115;
"DQ28_A"
$PN"47"113;
"DQ27_A"
$PN"187"52;
"DQ26_A"
$PN"185"53;
"DQ25_A"
$PN"42"54;
"DQ24_A"
$PN"40"55;
"DQ23_A"
$PN"183"56;
"DQ22_A"
$PN"181"57;
"DQ21_A"
$PN"38"58;
"DQ20_A"
$PN"36"59;
"DQ19_A"
$PN"176"60;
"DQ18_A"
$PN"174"61;
"DQ17_A"
$PN"31"62;
"DQ16_A"
$PN"29"158;
"DQ15_A"
$PN"172"159;
"DQ14_A"
$PN"170"63;
"DQ13_A"
$PN"27"64;
"DQ12_A"
$PN"25"65;
"DQ11_A"
$PN"165"66;
"DQ10_A"
$PN"163"67;
"DQ9_A"
$PN"20"68;
"DQ8_A"
$PN"18"69;
"DQ7_A"
$PN"161"70;
"DQ6_A"
$PN"159"71;
"DQ5_A"
$PN"16"72;
"DQ4_A"
$PN"14"73;
"DQ3_A"
$PN"154"74;
"DQ2_A"
$PN"152"75;
"DQ1_A"
$PN"9"76;
"DQ0_A"
$PN"7"77;
"DQ31_B"
$PN"287"78;
"DQ30_B"
$PN"285"79;
"DQ29_B"
$PN"142"80;
"DQ28_B"
$PN"140"81;
"DQ27_B"
$PN"280"82;
"DQ26_B"
$PN"278"83;
"DQ25_B"
$PN"135"84;
"DQ24_B"
$PN"133"85;
"DQ23_B"
$PN"276"86;
"DQ22_B"
$PN"274"87;
"DQ21_B"
$PN"131"88;
"DQ20_B"
$PN"129"89;
"DQ19_B"
$PN"269"90;
"DQ18_B"
$PN"267"91;
"DQ17_B"
$PN"124"92;
"DQ16_B"
$PN"122"93;
"DQ15_B"
$PN"265"18;
"DQ14_B"
$PN"263"94;
"DQ13_B"
$PN"120"95;
"DQ12_B"
$PN"118"96;
"DQ11_B"
$PN"258"97;
"DQ10_B"
$PN"256"98;
"DQ9_B"
$PN"113"99;
"DQ8_B"
$PN"111"100;
"DQ7_B"
$PN"254"101;
"DQ6_B"
$PN"252"102;
"DQ5_B"
$PN"109"103;
"DQ4_B"
$PN"107"104;
"DQ3_B"
$PN"247"105;
"DQ2_B"
$PN"245"106;
"DQ1_B"
$PN"102"107;
"DQ0_B"
$PN"100"108;
"HAS"
$PN"148"167;
"HSCL"
$PN"4"168;
"HSDA"
$PN"5"171;
"LBD||RSP_A_N"
$PN"86"109;
"LBS||RSP_B_N"
$PN"87"110;
"PAR_A"
$PN"74"111;
"PAR_B"
$PN"227"112;
"RESET_N \B"
$PN"207"16;
"RFU6"
$PN"232"0;
"RFU5"
$PN"231"0;
"RFU4"
$PN"220"0;
"RFU3"
$PN"150"0;
"RFU2"
$PN"149"0;
"RFU1"
$PN"144"0;
"RFU0"
$PN"2"0;
"VIN_MGMT"
$PN"3"172;
%"TAP"
"1","(-3425,3375)","0","mstr_standard","I220";
;
CDS_LIB"mstr_standard"
BODY_TYPE"PLUMBING"
HDL_TAP"TRUE";
"B \NAC \NWC"8;
"S \NAC"
BN"9"156;
%"TAP"
"1","(-3425,3275)","0","mstr_standard","I221";
;
CDS_LIB"mstr_standard"
BODY_TYPE"PLUMBING"
HDL_TAP"TRUE";
"B \NAC \NWC"8;
"S \NAC"
BN"8"120;
%"TAP"
"1","(-3225,3125)","0","mstr_standard","I222";
;
CDS_LIB"mstr_standard"
BODY_TYPE"PLUMBING"
HDL_TAP"TRUE";
"B \NAC \NWC"9;
"S \NAC"
BN"7"151;
%"TAP"
"1","(-3225,3025)","0","mstr_standard","I223";
;
CDS_LIB"mstr_standard"
BODY_TYPE"PLUMBING"
HDL_TAP"TRUE";
"B \NAC \NWC"9;
"S \NAC"
BN"6"148;
%"TAP"
"1","(-3225,2925)","0","mstr_standard","I224";
;
CDS_LIB"mstr_standard"
BODY_TYPE"PLUMBING"
HDL_TAP"TRUE";
"B \NAC \NWC"9;
"S \NAC"
BN"5"145;
%"TAP"
"1","(-3225,2725)","0","mstr_standard","I225";
;
CDS_LIB"mstr_standard"
BODY_TYPE"PLUMBING"
HDL_TAP"TRUE";
"B \NAC \NWC"9;
"S \NAC"
BN"3"137;
%"TAP"
"1","(-3225,2825)","0","mstr_standard","I226";
;
CDS_LIB"mstr_standard"
BODY_TYPE"PLUMBING"
HDL_TAP"TRUE";
"B \NAC \NWC"9;
"S \NAC"
BN"4"141;
%"TAP"
"1","(-3225,2625)","0","mstr_standard","I227";
;
CDS_LIB"mstr_standard"
BODY_TYPE"PLUMBING"
HDL_TAP"TRUE";
"B \NAC \NWC"9;
"S \NAC"
BN"2"133;
%"TAP"
"1","(-3225,2525)","0","mstr_standard","I228";
;
CDS_LIB"mstr_standard"
BODY_TYPE"PLUMBING"
HDL_TAP"TRUE";
"B \NAC \NWC"9;
"S \NAC"
BN"1"129;
%"TAP"
"1","(-3225,2425)","0","mstr_standard","I229";
;
CDS_LIB"mstr_standard"
BODY_TYPE"PLUMBING"
HDL_TAP"TRUE";
"B \NAC \NWC"9;
"S \NAC"
BN"0"125;
%"TAP"
"1","(-7650,3300)","2","mstr_standard","I23";
;
CDS_LIB"mstr_standard"
BODY_TYPE"PLUMBING"
HDL_TAP"TRUE";
"B \NAC \NWC"4;
"S \NAC"
BN"2"44;
%"TAP"
"1","(-3425,3175)","0","mstr_standard","I230";
;
CDS_LIB"mstr_standard"
BODY_TYPE"PLUMBING"
HDL_TAP"TRUE";
"B \NAC \NWC"8;
"S \NAC"
BN"7"122;
%"TAP"
"1","(-3425,3075)","0","mstr_standard","I231";
;
CDS_LIB"mstr_standard"
BODY_TYPE"PLUMBING"
HDL_TAP"TRUE";
"B \NAC \NWC"8;
"S \NAC"
BN"6"149;
%"TAP"
"1","(-3425,2975)","0","mstr_standard","I232";
;
CDS_LIB"mstr_standard"
BODY_TYPE"PLUMBING"
HDL_TAP"TRUE";
"B \NAC \NWC"8;
"S \NAC"
BN"5"146;
%"TAP"
"1","(-3425,2875)","0","mstr_standard","I233";
;
CDS_LIB"mstr_standard"
BODY_TYPE"PLUMBING"
HDL_TAP"TRUE";
"B \NAC \NWC"8;
"S \NAC"
BN"4"142;
%"TAP"
"1","(-3425,2775)","0","mstr_standard","I234";
;
CDS_LIB"mstr_standard"
BODY_TYPE"PLUMBING"
HDL_TAP"TRUE";
"B \NAC \NWC"8;
"S \NAC"
BN"3"138;
%"TAP"
"1","(-3425,2675)","0","mstr_standard","I235";
;
CDS_LIB"mstr_standard"
BODY_TYPE"PLUMBING"
HDL_TAP"TRUE";
"B \NAC \NWC"8;
"S \NAC"
BN"2"134;
%"TAP"
"1","(-3425,2575)","0","mstr_standard","I236";
;
CDS_LIB"mstr_standard"
BODY_TYPE"PLUMBING"
HDL_TAP"TRUE";
"B \NAC \NWC"8;
"S \NAC"
BN"1"130;
%"TAP"
"1","(-3425,2475)","0","mstr_standard","I237";
;
CDS_LIB"mstr_standard"
BODY_TYPE"PLUMBING"
HDL_TAP"TRUE";
"B \NAC \NWC"8;
"S \NAC"
BN"0"126;
%"SCONN288_DDR506112002KQ"
"2","(-4375,3425)","0","pure_quanta","I238";
;
LOCATION"J27"
$SEC"2"
CDS_SEC"2"
PART_TYPE"SMLF"
MATERIAL"IO"
VALUE"SCONN288_DDR506112002KQ"
CDS_LMAN_SYM_OUTLINE"-600,1150,600,-1150"
NEEDS_NO_SIZE"TRUE"
CDS_LIB"pure_quanta"
PART_NUMBER"DFHST8FS479";
"DQS7_A_C||TDQS7_A_C \B"
$PN"178"118;
"DQS6_A_T||TDQS6_A_T"
$PN"168"119;
"DQS8_B_T||TDQS8_B_T"
$PN"283"120;
"DQS8_B_C||TDQS8_B_C \B"
$PN"282"121;
"DQS7_B_T||TDQS7_B_T"
$PN"272"122;
"DQS0_A_C \B"
$PN"12"123;
"DQS0_A_T"
$PN"11"124;
"DQS0_B_C \B"
$PN"105"125;
"DQS0_B_T"
$PN"104"126;
"DQS1_A_C \B"
$PN"23"127;
"DQS1_A_T"
$PN"22"128;
"DQS1_B_C \B"
$PN"116"129;
"DQS1_B_T"
$PN"115"130;
"DQS2_A_C \B"
$PN"34"131;
"DQS2_A_T"
$PN"33"132;
"DQS2_B_C \B"
$PN"127"133;
"DQS2_B_T"
$PN"126"134;
"DQS3_A_C \B"
$PN"45"135;
"DQS3_A_T"
$PN"44"136;
"DQS3_B_C \B"
$PN"138"137;
"DQS3_B_T"
$PN"137"138;
"DQS4_A_C \B"
$PN"56"139;
"DQS4_A_T"
$PN"55"140;
"DQS4_B_C \B"
$PN"238"141;
"DQS4_B_T"
$PN"239"142;
"DQS5_A_C||TDQS5_A_C||DQS5_A_T||TDQS5_A_T \B"
$PN"156"143;
"DQS5_A_T||TDQS5_A_T"
$PN"157"144;
"DQS5_B_C||TDQS5_B_C \B"
$PN"249"145;
"DQS5_B_T||TDQS5_B_T"
$PN"250"146;
"DQS6_A_C||TDQS6_A_C||DQS6_A_T||TDQS6_A_T \B"
$PN"167"147;
"DQS6_B_C||TDQS6_B_C \B"
$PN"260"148;
"DQS6_B_T||TDQS6_B_T"
$PN"261"149;
"DQS7_A_T||TDQS7_A_T"
$PN"179"150;
"DQS7_B_C||TDQS7_B_C \B"
$PN"271"151;
"DQS8_A_C||TDQS8_A_C \B"
$PN"189"152;
"DQS8_A_T||TDQS8_A_T"
$PN"190"153;
"DQS9_A_C||TDQS9_A_C \B"
$PN"200"157;
"DQS9_A_T||TDQS9_A_T"
$PN"201"154;
"DQS9_B_C||TDQS9_B_C \B"
$PN"94"155;
"DQS9_B_T||TDQS9_B_T||DBI4_B_N"
$PN"93"156;
%"GND"
"1","(-2825,5525)","0","pure_quanta_power","I239";
;
CDS_LIB"pure_quanta_power"
BOM_COST"MEM"
SIZE"1B"
ROOM"MEM_EFGH_DECOUPLING_CAPS"
HDL_POWER"GND";
"A<SIZE-1..0>\NAC"164;
%"TAP"
"1","(-7650,3350)","2","mstr_standard","I24";
;
CDS_LIB"mstr_standard"
BODY_TYPE"PLUMBING"
HDL_TAP"TRUE";
"B \NAC \NWC"4;
"S \NAC"
BN"3"43;
%"Q_CAP"
"1","(-2825,5875)","2","pure_quanta","I240";
;
LOCATION"C532"
$SEC"1"
CDS_SEC"1"
PACK_TYPE"C0805"
VOLTAGE"25V"
VALUE"10UF"
TOLERANCE"10%"
MATERIAL"X6S"
CDS_LIB"pure_quanta"
BOM_COST"MEM"
ROOM""
PART_NUMBER"CH6104KEA00";
"B"
$PN"2"164;
"A"
$PN"1"163;
%"Q_CAP"
"1","(-2250,5875)","2","pure_quanta","I241";
;
LOCATION"C533"
$SEC"1"
CDS_SEC"1"
PACK_TYPE"C0805"
VOLTAGE"25V"
VALUE"10UF"
TOLERANCE"10%"
MATERIAL"X6S"
CDS_LIB"pure_quanta"
BOM_COST"MEM"
ROOM""
PART_NUMBER"CH6104KEA00";
"B"
$PN"2"164;
"A"
$PN"1"163;
%"UNIVERSAL_POWER"
"1","(-2825,6200)","0","pure_quanta_power","I242";
;
HDL_POWER"P12V_MEM_CPU1"
CDS_LIB"pure_quanta_power";
"A"163;
%"Q_RES"
"1","(-7700,2625)","0","pure_quanta","I244";
;
LOCATION"R1587"
$SEC"1"
CDS_SEC"1"
VALUE"49.9"
CDS_LIB"pure_quanta"
MATERIAL"CHIP"
PACK_TYPE"0402LF"
WATTAGE"1/16W"
TOLERANCE"1%"
PART_NUMBER"CS04992FB07";
"B"
$PN"2"168;
"A"
$PN"1"170;
%"Q_RES"
"1","(-8050,2850)","0","pure_quanta","I245";
;
LOCATION"R1707"
$SEC"1"
CDS_SEC"1"
VALUE"10"
PACK_TYPE"0402LF"
MATERIAL"CHIP"
CDS_LIB"pure_quanta"
WATTAGE"1/16W"
TOLERANCE"1%"
PART_NUMBER"CS01002FB07";
"B"
$PN"2"171;
"A"
$PN"1"169;
%"TAP"
"1","(-7650,3250)","2","mstr_standard","I25";
;
CDS_LIB"mstr_standard"
BODY_TYPE"PLUMBING"
HDL_TAP"TRUE";
"B \NAC \NWC"4;
"S \NAC"
BN"1"45;
%"TAP"
"1","(-7650,3200)","2","mstr_standard","I26";
;
CDS_LIB"mstr_standard"
BODY_TYPE"PLUMBING"
HDL_TAP"TRUE";
"B \NAC \NWC"4;
"S \NAC"
BN"0"17;
%"TAP"
"1","(-7650,3400)","2","mstr_standard","I27";
;
CDS_LIB"mstr_standard"
BODY_TYPE"PLUMBING"
HDL_TAP"TRUE";
"B \NAC \NWC"4;
"S \NAC"
BN"4"42;
%"TAP"
"1","(-7650,3450)","2","mstr_standard","I28";
;
CDS_LIB"mstr_standard"
BODY_TYPE"PLUMBING"
HDL_TAP"TRUE";
"B \NAC \NWC"4;
"S \NAC"
BN"5"41;
%"TAP"
"1","(-7650,3500)","2","mstr_standard","I29";
;
CDS_LIB"mstr_standard"
BODY_TYPE"PLUMBING"
HDL_TAP"TRUE";
"B \NAC \NWC"4;
"S \NAC"
BN"6"40;
%"TAP"
"1","(-7650,3550)","2","mstr_standard","I30";
;
CDS_LIB"mstr_standard"
BODY_TYPE"PLUMBING"
HDL_TAP"TRUE";
"B \NAC \NWC"4;
"S \NAC"
BN"7"161;
%"TAP"
"1","(-7650,3650)","2","mstr_standard","I31";
;
CDS_LIB"mstr_standard"
BODY_TYPE"PLUMBING"
HDL_TAP"TRUE";
"B \NAC \NWC"5;
"S \NAC"
BN"0"19;
%"TAP"
"1","(-7650,3700)","2","mstr_standard","I32";
;
CDS_LIB"mstr_standard"
BODY_TYPE"PLUMBING"
HDL_TAP"TRUE";
"B \NAC \NWC"5;
"S \NAC"
BN"1"160;
%"TAP"
"1","(-7650,3750)","2","mstr_standard","I33";
;
CDS_LIB"mstr_standard"
BODY_TYPE"PLUMBING"
HDL_TAP"TRUE";
"B \NAC \NWC"5;
"S \NAC"
BN"2"39;
%"TAP"
"1","(-7650,3800)","2","mstr_standard","I34";
;
CDS_LIB"mstr_standard"
BODY_TYPE"PLUMBING"
HDL_TAP"TRUE";
"B \NAC \NWC"5;
"S \NAC"
BN"3"38;
%"TAP"
"1","(-7650,3850)","2","mstr_standard","I35";
;
CDS_LIB"mstr_standard"
BODY_TYPE"PLUMBING"
HDL_TAP"TRUE";
"B \NAC \NWC"5;
"S \NAC"
BN"4"23;
%"TAP"
"1","(-5950,2200)","0","mstr_standard","I36";
;
CDS_LIB"mstr_standard"
BODY_TYPE"PLUMBING"
HDL_TAP"TRUE";
"B \NAC \NWC"12;
"S \NAC"
BN"0"108;
%"TAP"
"1","(-5950,2300)","0","mstr_standard","I37";
;
CDS_LIB"mstr_standard"
BODY_TYPE"PLUMBING"
HDL_TAP"TRUE";
"B \NAC \NWC"12;
"S \NAC"
BN"2"106;
%"TAP"
"1","(-5950,2350)","0","mstr_standard","I38";
;
CDS_LIB"mstr_standard"
BODY_TYPE"PLUMBING"
HDL_TAP"TRUE";
"B \NAC \NWC"12;
"S \NAC"
BN"3"105;
%"TAP"
"1","(-5950,2250)","0","mstr_standard","I39";
;
CDS_LIB"mstr_standard"
BODY_TYPE"PLUMBING"
HDL_TAP"TRUE";
"B \NAC \NWC"12;
"S \NAC"
BN"1"107;
%"TAP"
"1","(-5950,2400)","0","mstr_standard","I40";
;
CDS_LIB"mstr_standard"
BODY_TYPE"PLUMBING"
HDL_TAP"TRUE";
"B \NAC \NWC"12;
"S \NAC"
BN"4"104;
%"TAP"
"1","(-5950,2450)","0","mstr_standard","I41";
;
CDS_LIB"mstr_standard"
BODY_TYPE"PLUMBING"
HDL_TAP"TRUE";
"B \NAC \NWC"12;
"S \NAC"
BN"5"103;
%"TAP"
"1","(-5950,2500)","0","mstr_standard","I42";
;
CDS_LIB"mstr_standard"
BODY_TYPE"PLUMBING"
HDL_TAP"TRUE";
"B \NAC \NWC"12;
"S \NAC"
BN"6"102;
%"TAP"
"1","(-5950,2550)","0","mstr_standard","I43";
;
CDS_LIB"mstr_standard"
BODY_TYPE"PLUMBING"
HDL_TAP"TRUE";
"B \NAC \NWC"12;
"S \NAC"
BN"7"101;
%"TAP"
"1","(-5950,2600)","0","mstr_standard","I44";
;
CDS_LIB"mstr_standard"
BODY_TYPE"PLUMBING"
HDL_TAP"TRUE";
"B \NAC \NWC"12;
"S \NAC"
BN"8"100;
%"TAP"
"1","(-5950,2650)","0","mstr_standard","I45";
;
CDS_LIB"mstr_standard"
BODY_TYPE"PLUMBING"
HDL_TAP"TRUE";
"B \NAC \NWC"12;
"S \NAC"
BN"9"99;
%"TAP"
"1","(-5950,2700)","0","mstr_standard","I46";
;
CDS_LIB"mstr_standard"
BODY_TYPE"PLUMBING"
HDL_TAP"TRUE";
"B \NAC \NWC"12;
"S \NAC"
BN"10"98;
%"TAP"
"1","(-5950,2750)","0","mstr_standard","I47";
;
CDS_LIB"mstr_standard"
BODY_TYPE"PLUMBING"
HDL_TAP"TRUE";
"B \NAC \NWC"12;
"S \NAC"
BN"11"97;
%"TAP"
"1","(-5950,2850)","0","mstr_standard","I48";
;
CDS_LIB"mstr_standard"
BODY_TYPE"PLUMBING"
HDL_TAP"TRUE";
"B \NAC \NWC"12;
"S \NAC"
BN"13"95;
%"TAP"
"1","(-5950,2800)","0","mstr_standard","I49";
;
CDS_LIB"mstr_standard"
BODY_TYPE"PLUMBING"
HDL_TAP"TRUE";
"B \NAC \NWC"12;
"S \NAC"
BN"12"96;
%"TAP"
"1","(-5950,2900)","0","mstr_standard","I50";
;
CDS_LIB"mstr_standard"
BODY_TYPE"PLUMBING"
HDL_TAP"TRUE";
"B \NAC \NWC"12;
"S \NAC"
BN"14"94;
%"TAP"
"1","(-5950,2950)","0","mstr_standard","I51";
;
CDS_LIB"mstr_standard"
BODY_TYPE"PLUMBING"
HDL_TAP"TRUE";
"B \NAC \NWC"12;
"S \NAC"
BN"15"18;
%"TAP"
"1","(-5950,3000)","0","mstr_standard","I52";
;
CDS_LIB"mstr_standard"
BODY_TYPE"PLUMBING"
HDL_TAP"TRUE";
"B \NAC \NWC"12;
"S \NAC"
BN"16"93;
%"TAP"
"1","(-5950,3050)","0","mstr_standard","I53";
;
CDS_LIB"mstr_standard"
BODY_TYPE"PLUMBING"
HDL_TAP"TRUE";
"B \NAC \NWC"12;
"S \NAC"
BN"17"92;
%"TAP"
"1","(-5950,3100)","0","mstr_standard","I54";
;
CDS_LIB"mstr_standard"
BODY_TYPE"PLUMBING"
HDL_TAP"TRUE";
"B \NAC \NWC"12;
"S \NAC"
BN"18"91;
%"TAP"
"1","(-5950,3150)","0","mstr_standard","I55";
;
CDS_LIB"mstr_standard"
BODY_TYPE"PLUMBING"
HDL_TAP"TRUE";
"B \NAC \NWC"12;
"S \NAC"
BN"19"90;
%"TAP"
"1","(-5950,3200)","0","mstr_standard","I56";
;
CDS_LIB"mstr_standard"
BODY_TYPE"PLUMBING"
HDL_TAP"TRUE";
"B \NAC \NWC"12;
"S \NAC"
BN"20"89;
%"TAP"
"1","(-5950,3250)","0","mstr_standard","I57";
;
CDS_LIB"mstr_standard"
BODY_TYPE"PLUMBING"
HDL_TAP"TRUE";
"B \NAC \NWC"12;
"S \NAC"
BN"21"88;
%"TAP"
"1","(-5950,3300)","0","mstr_standard","I58";
;
CDS_LIB"mstr_standard"
BODY_TYPE"PLUMBING"
HDL_TAP"TRUE";
"B \NAC \NWC"12;
"S \NAC"
BN"22"87;
%"TAP"
"1","(-5950,3350)","0","mstr_standard","I59";
;
CDS_LIB"mstr_standard"
BODY_TYPE"PLUMBING"
HDL_TAP"TRUE";
"B \NAC \NWC"12;
"S \NAC"
BN"23"86;
%"TAP"
"1","(-5950,3400)","0","mstr_standard","I60";
;
CDS_LIB"mstr_standard"
BODY_TYPE"PLUMBING"
HDL_TAP"TRUE";
"B \NAC \NWC"12;
"S \NAC"
BN"24"85;
%"TAP"
"1","(-5950,3450)","0","mstr_standard","I61";
;
CDS_LIB"mstr_standard"
BODY_TYPE"PLUMBING"
HDL_TAP"TRUE";
"B \NAC \NWC"12;
"S \NAC"
BN"25"84;
%"TAP"
"1","(-5950,3500)","0","mstr_standard","I62";
;
CDS_LIB"mstr_standard"
BODY_TYPE"PLUMBING"
HDL_TAP"TRUE";
"B \NAC \NWC"12;
"S \NAC"
BN"26"83;
%"TAP"
"1","(-5950,3550)","0","mstr_standard","I63";
;
CDS_LIB"mstr_standard"
BODY_TYPE"PLUMBING"
HDL_TAP"TRUE";
"B \NAC \NWC"12;
"S \NAC"
BN"27"82;
%"TAP"
"1","(-5950,3600)","0","mstr_standard","I64";
;
CDS_LIB"mstr_standard"
BODY_TYPE"PLUMBING"
HDL_TAP"TRUE";
"B \NAC \NWC"12;
"S \NAC"
BN"28"81;
%"TAP"
"1","(-5950,3650)","0","mstr_standard","I65";
;
CDS_LIB"mstr_standard"
BODY_TYPE"PLUMBING"
HDL_TAP"TRUE";
"B \NAC \NWC"12;
"S \NAC"
BN"29"80;
%"TAP"
"1","(-5950,3750)","0","mstr_standard","I66";
;
CDS_LIB"mstr_standard"
BODY_TYPE"PLUMBING"
HDL_TAP"TRUE";
"B \NAC \NWC"12;
"S \NAC"
BN"31"78;
%"TAP"
"1","(-5950,3700)","0","mstr_standard","I67";
;
CDS_LIB"mstr_standard"
BODY_TYPE"PLUMBING"
HDL_TAP"TRUE";
"B \NAC \NWC"12;
"S \NAC"
BN"30"79;
%"TAP"
"1","(-5950,3850)","0","mstr_standard","I68";
;
CDS_LIB"mstr_standard"
BODY_TYPE"PLUMBING"
HDL_TAP"TRUE";
"B \NAC \NWC"6;
"S \NAC"
BN"0"77;
%"TAP"
"1","(-7650,4000)","2","mstr_standard","I77";
;
CDS_LIB"mstr_standard"
BODY_TYPE"PLUMBING"
HDL_TAP"TRUE";
"B \NAC \NWC"5;
"S \NAC"
BN"7"22;
%"TAP"
"1","(-7650,3950)","2","mstr_standard","I78";
;
CDS_LIB"mstr_standard"
BODY_TYPE"PLUMBING"
HDL_TAP"TRUE";
"B \NAC \NWC"5;
"S \NAC"
BN"6"36;
%"TAP"
"1","(-7650,3900)","2","mstr_standard","I79";
;
CDS_LIB"mstr_standard"
BODY_TYPE"PLUMBING"
HDL_TAP"TRUE";
"B \NAC \NWC"5;
"S \NAC"
BN"5"37;
%"TAP"
"1","(-7650,4850)","2","mstr_standard","I80";
;
CDS_LIB"mstr_standard"
BODY_TYPE"PLUMBING"
HDL_TAP"TRUE";
"B \NAC \NWC"13;
"S \NAC"
BN"3"31;
%"TAP"
"1","(-7650,4800)","2","mstr_standard","I81";
;
CDS_LIB"mstr_standard"
BODY_TYPE"PLUMBING"
HDL_TAP"TRUE";
"B \NAC \NWC"13;
"S \NAC"
BN"2"29;
%"TAP"
"1","(-7650,4750)","2","mstr_standard","I82";
;
CDS_LIB"mstr_standard"
BODY_TYPE"PLUMBING"
HDL_TAP"TRUE";
"B \NAC \NWC"13;
"S \NAC"
BN"1"27;
%"TAP"
"1","(-7650,4700)","2","mstr_standard","I83";
;
CDS_LIB"mstr_standard"
BODY_TYPE"PLUMBING"
HDL_TAP"TRUE";
"B \NAC \NWC"13;
"S \NAC"
BN"0"25;
%"TAP"
"1","(-7650,4900)","2","mstr_standard","I84";
;
CDS_LIB"mstr_standard"
BODY_TYPE"PLUMBING"
HDL_TAP"TRUE";
"B \NAC \NWC"13;
"S \NAC"
BN"4"32;
%"TAP"
"1","(-7650,4950)","2","mstr_standard","I85";
;
CDS_LIB"mstr_standard"
BODY_TYPE"PLUMBING"
HDL_TAP"TRUE";
"B \NAC \NWC"13;
"S \NAC"
BN"5"33;
%"TAP"
"1","(-7650,5000)","2","mstr_standard","I86";
;
CDS_LIB"mstr_standard"
BODY_TYPE"PLUMBING"
HDL_TAP"TRUE";
"B \NAC \NWC"13;
"S \NAC"
BN"6"35;
%"TAP"
"1","(-7650,5150)","2","mstr_standard","I87";
;
CDS_LIB"mstr_standard"
BODY_TYPE"PLUMBING"
HDL_TAP"TRUE";
"B \NAC \NWC"11;
"S \NAC"
BN"1"26;
%"TAP"
"1","(-7650,5100)","2","mstr_standard","I88";
;
CDS_LIB"mstr_standard"
BODY_TYPE"PLUMBING"
HDL_TAP"TRUE";
"B \NAC \NWC"11;
"S \NAC"
BN"0"24;
%"TAP"
"1","(-7650,5200)","2","mstr_standard","I89";
;
CDS_LIB"mstr_standard"
BODY_TYPE"PLUMBING"
HDL_TAP"TRUE";
"B \NAC \NWC"11;
"S \NAC"
BN"2"28;
%"VCC_CORE"
"1","(-8475,3425)","0","mstr_symbols","I9";
;
HDL_POWER"P3V3_AUX"
CDS_LIB"mstr_symbols"
VOLTAGE"3.3"
ROOM"PVCCINFAON_CPU1_CTRL";
"A"172;
%"TAP"
"1","(-7650,5250)","2","mstr_standard","I90";
;
CDS_LIB"mstr_standard"
BODY_TYPE"PLUMBING"
HDL_TAP"TRUE";
"B \NAC \NWC"11;
"S \NAC"
BN"3"30;
%"TAP"
"1","(-7650,5300)","2","mstr_standard","I91";
;
CDS_LIB"mstr_standard"
BODY_TYPE"PLUMBING"
HDL_TAP"TRUE";
"B \NAC \NWC"11;
"S \NAC"
BN"4"116;
%"TAP"
"1","(-7650,5400)","2","mstr_standard","I92";
;
CDS_LIB"mstr_standard"
BODY_TYPE"PLUMBING"
HDL_TAP"TRUE";
"B \NAC \NWC"11;
"S \NAC"
BN"6"34;
%"TAP"
"1","(-7650,5350)","2","mstr_standard","I93";
;
CDS_LIB"mstr_standard"
BODY_TYPE"PLUMBING"
HDL_TAP"TRUE";
"B \NAC \NWC"11;
"S \NAC"
BN"5"117;
%"TAP"
"1","(-5950,3900)","0","mstr_standard","I94";
;
CDS_LIB"mstr_standard"
BODY_TYPE"PLUMBING"
HDL_TAP"TRUE";
"B \NAC \NWC"6;
"S \NAC"
BN"1"76;
%"TAP"
"1","(-5950,3950)","0","mstr_standard","I95";
;
CDS_LIB"mstr_standard"
BODY_TYPE"PLUMBING"
HDL_TAP"TRUE";
"B \NAC \NWC"6;
"S \NAC"
BN"2"75;
%"TAP"
"1","(-5950,4000)","0","mstr_standard","I96";
;
CDS_LIB"mstr_standard"
BODY_TYPE"PLUMBING"
HDL_TAP"TRUE";
"B \NAC \NWC"6;
"S \NAC"
BN"3"74;
%"TAP"
"1","(-5950,4150)","0","mstr_standard","I97";
;
CDS_LIB"mstr_standard"
BODY_TYPE"PLUMBING"
HDL_TAP"TRUE";
"B \NAC \NWC"6;
"S \NAC"
BN"6"71;
%"TAP"
"1","(-5950,4050)","0","mstr_standard","I98";
;
CDS_LIB"mstr_standard"
BODY_TYPE"PLUMBING"
HDL_TAP"TRUE";
"B \NAC \NWC"6;
"S \NAC"
BN"4"73;
%"TAP"
"1","(-5950,4100)","0","mstr_standard","I99";
;
CDS_LIB"mstr_standard"
BODY_TYPE"PLUMBING"
HDL_TAP"TRUE";
"B \NAC \NWC"6;
"S \NAC"
BN"5"72;
END.
